# T6G (Grand Teton) — schematic netlist excerpt (pin names and nets, part order shuffled) for the footprints in the layout excerpt that follows; sources: Cadence DE-HDL packaged netlist, KiCad conversion of 04192023_DAF0TMB3IC0_F0TG_MB_C_brd_V02_OCP.brd

C333  Q_CAP  10UF 6.3V 20% X6S  pkg C0402  page 334 : A = P0V9_CPU1_RT_2D ; B = GND
C2334  Q_CAP  0.1UF 25V 10% X7R  pkg 0402  page 182 : A = P3V3_9ZXL045_P0_VDDA ; B = GND

(kicad_pcb
	(version 20260206)
	(generator "pcbnew")
	(generator_version "10.0")
	(general
		(thickness 1.6)
		(legacy_teardrops no)
	)
	(paper "A4")
	(title_block
		(title "04192023_DAF0TMB3IC0_F0TG_MB_C_brd_V02_OCP.brd")
		(comment 1 "Grand Teton / footprints 5022-5023 of 8354")
	)
	(layers
		(0 "F.Cu" signal "TOP")
		(4 "In1.Cu" signal "GND")
		(6 "In2.Cu" signal "IN1")
		(8 "In3.Cu" signal "GND1")
		(10 "In4.Cu" signal "IN2")
		(12 "In5.Cu" signal "GND2")
		(14 "In6.Cu" signal "IN3")
		(16 "In7.Cu" signal "GND3")
		(18 "In8.Cu" signal "VCC")
		(20 "In9.Cu" signal "VCC1")
		(22 "In10.Cu" signal "GND4")
		(24 "In11.Cu" signal "IN4")
		(26 "In12.Cu" signal "GND5")
		(28 "In13.Cu" signal "IN5")
		(30 "In14.Cu" signal "GND6")
		(32 "In15.Cu" signal "IN6")
		(34 "In16.Cu" signal "GND7")
		(2 "B.Cu" signal "BOTTOM")
		(9 "F.Adhes" user "F.Adhesive")
		(11 "B.Adhes" user "B.Adhesive")
		(13 "F.Paste" user "Package Geometry/Pastemask Top")
		(15 "B.Paste" user "Package Geometry/Pastemask Bottom")
		(5 "F.SilkS" user "Ref Des/Silkscreen Top")
		(7 "B.SilkS" user "Ref Des/Silkscreen Bottom")
		(1 "F.Mask" user "Board Geometry/Soldermask Top")
		(3 "B.Mask" user "Board Geometry/Soldermask Bottom")
		(17 "Dwgs.User" user "User.Drawings")
		(19 "Cmts.User" user "User.Comments")
		(21 "Eco1.User" user "User.Eco1")
		(23 "Eco2.User" user "User.Eco2")
		(25 "Edge.Cuts" user "Board Geometry/Outline")
		(27 "Margin" user)
		(31 "F.CrtYd" user "Package Geometry/Place Bound Top")
		(29 "B.CrtYd" user "Package Geometry/Place Bound Bottom")
		(35 "F.Fab" user "Ref Des/Assembly Top")
		(33 "B.Fab" user "Ref Des/Assembly Bottom")
	)
	(footprint ""
		(layer "B.Cu")
		(at 87.118952 -390.560052 90)
		(property "Reference" "C333"
			(at 0 0 90)
			(layer "B.SilkS")
			(hide yes)
			(effects
				(font
					(size 1.27 1.27)
				)
				(justify mirror)
			)
		)
		(property "Value" ""
			(at 0 0 90)
			(layer "B.Fab")
			(effects
				(font
					(size 1.27 1.27)
				)
				(justify mirror)
			)
		)
		(duplicate_pad_numbers_are_jumpers no)
		(fp_line
			(start 0.7874 -0.4064)
			(end -0.7874 -0.4064)
			(stroke
				(width 0.1524)
				(type default)
			)
			(layer "B.SilkS")
		)
		(fp_line
			(start -0.7874 -0.4064)
			(end -0.7874 0.4064)
			(stroke
				(width 0.1524)
				(type default)
			)
			(layer "B.SilkS")
		)
		(fp_line
			(start 0.7874 0.4064)
			(end 0.7874 -0.4064)
			(stroke
				(width 0.1524)
				(type default)
			)
			(layer "B.SilkS")
		)
		(fp_line
			(start -0.7874 0.4064)
			(end 0.7874 0.4064)
			(stroke
				(width 0.1524)
				(type default)
			)
			(layer "B.SilkS")
		)
		(fp_line
			(start 0.67945 -0.305054)
			(end 0.12065 -0.305054)
			(stroke
				(width 0.1)
				(type default)
			)
			(layer "B.Fab")
		)
		(fp_line
			(start 0.12065 -0.305054)
			(end 0.12065 -0.2794)
			(stroke
				(width 0.1)
				(type default)
			)
			(layer "B.Fab")
		)
		(fp_line
			(start -0.12065 -0.3048)
			(end -0.67945 -0.3048)
			(stroke
				(width 0.1)
				(type default)
			)
			(layer "B.Fab")
		)
		(fp_line
			(start -0.67945 -0.3048)
			(end -0.67945 0.3048)
			(stroke
				(width 0.1)
				(type default)
			)
			(layer "B.Fab")
		)
		(fp_line
			(start 0.12065 -0.2794)
			(end -0.12065 -0.2794)
			(stroke
				(width 0.1)
				(type default)
			)
			(layer "B.Fab")
		)
		(fp_line
			(start -0.12065 -0.2794)
			(end -0.12065 -0.3048)
			(stroke
				(width 0.1)
				(type default)
			)
			(layer "B.Fab")
		)
		(fp_line
			(start 0.12065 0.2794)
			(end 0.12065 0.3048)
			(stroke
				(width 0.1)
				(type default)
			)
			(layer "B.Fab")
		)
		(fp_line
			(start -0.120396 0.2794)
			(end 0.12065 0.2794)
			(stroke
				(width 0.1)
				(type default)
			)
			(layer "B.Fab")
		)
		(fp_line
			(start 0.67945 0.3048)
			(end 0.67945 -0.305054)
			(stroke
				(width 0.1)
				(type default)
			)
			(layer "B.Fab")
		)
		(fp_line
			(start 0.12065 0.3048)
			(end 0.67945 0.3048)
			(stroke
				(width 0.1)
				(type default)
			)
			(layer "B.Fab")
		)
		(fp_line
			(start -0.120396 0.3048)
			(end -0.120396 0.2794)
			(stroke
				(width 0.1)
				(type default)
			)
			(layer "B.Fab")
		)
		(fp_line
			(start -0.67945 0.3048)
			(end -0.120396 0.3048)
			(stroke
				(width 0.1)
				(type default)
			)
			(layer "B.Fab")
		)
		(pad "1" smd circle
			(at 0.40005 0 270)
			(size 0 0)
			(layers "B.Cu" "B.Mask" "B.Paste")
			(net "P0V9_CPU1_RT_2D")
		)
		(pad "2" smd circle
			(at -0.40005 0 270)
			(size 0 0)
			(layers "B.Cu" "B.Mask" "B.Paste")
			(net "GND")
		)
	)
	(footprint ""
		(layer "B.Cu")
		(at 284.074108 -420.491412 90)
		(property "Reference" "C2334"
			(at 0 0 90)
			(layer "B.SilkS")
			(hide yes)
			(effects
				(font
					(size 1.27 1.27)
				)
				(justify mirror)
			)
		)
		(property "Value" ""
			(at 0 0 90)
			(layer "B.Fab")
			(effects
				(font
					(size 1.27 1.27)
				)
				(justify mirror)
			)
		)
		(duplicate_pad_numbers_are_jumpers no)
		(fp_line
			(start 0.7874 -0.4064)
			(end -0.7874 -0.4064)
			(stroke
				(width 0.1524)
				(type default)
			)
			(layer "B.SilkS")
		)
		(fp_line
			(start -0.7874 -0.4064)
			(end -0.7874 0.4064)
			(stroke
				(width 0.1524)
				(type default)
			)
			(layer "B.SilkS")
		)
		(fp_line
			(start 0.7874 0.4064)
			(end 0.7874 -0.4064)
			(stroke
				(width 0.1524)
				(type default)
			)
			(layer "B.SilkS")
		)
		(fp_line
			(start -0.7874 0.4064)
			(end 0.7874 0.4064)
			(stroke
				(width 0.1524)
				(type default)
			)
			(layer "B.SilkS")
		)
		(fp_line
			(start 0.67945 -0.305054)
			(end 0.12065 -0.305054)
			(stroke
				(width 0.1)
				(type default)
			)
			(layer "B.Fab")
		)
		(fp_line
			(start 0.12065 -0.305054)
			(end 0.12065 -0.2794)
			(stroke
				(width 0.1)
				(type default)
			)
			(layer "B.Fab")
		)
		(fp_line
			(start -0.12065 -0.3048)
			(end -0.67945 -0.3048)
			(stroke
				(width 0.1)
				(type default)
			)
			(layer "B.Fab")
		)
		(fp_line
			(start -0.67945 -0.3048)
			(end -0.67945 0.3048)
			(stroke
				(width 0.1)
				(type default)
			)
			(layer "B.Fab")
		)
		(fp_line
			(start 0.12065 -0.2794)
			(end -0.12065 -0.2794)
			(stroke
				(width 0.1)
				(type default)
			)
			(layer "B.Fab")
		)
		(fp_line
			(start -0.12065 -0.2794)
			(end -0.12065 -0.3048)
			(stroke
				(width 0.1)
				(type default)
			)
			(layer "B.Fab")
		)
		(fp_line
			(start 0.12065 0.2794)
			(end 0.12065 0.3048)
			(stroke
				(width 0.1)
				(type default)
			)
			(layer "B.Fab")
		)
		(fp_line
			(start -0.120396 0.2794)
			(end 0.12065 0.2794)
			(stroke
				(width 0.1)
				(type default)
			)
			(layer "B.Fab")
		)
		(fp_line
			(start 0.67945 0.3048)
			(end 0.67945 -0.305054)
			(stroke
				(width 0.1)
				(type default)
			)
			(layer "B.Fab")
		)
		(fp_line
			(start 0.12065 0.3048)
			(end 0.67945 0.3048)
			(stroke
				(width 0.1)
				(type default)
			)
			(layer "B.Fab")
		)
		(fp_line
			(start -0.120396 0.3048)
			(end -0.120396 0.2794)
			(stroke
				(width 0.1)
				(type default)
			)
			(layer "B.Fab")
		)
		(fp_line
			(start -0.67945 0.3048)
			(end -0.120396 0.3048)
			(stroke
				(width 0.1)
				(type default)
			)
			(layer "B.Fab")
		)
		(pad "1" smd circle
			(at 0.40005 0 270)
			(size 0 0)
			(layers "B.Cu" "B.Mask" "B.Paste")
			(net "P3V3_9ZXL045_P0_VDDA")
		)
		(pad "2" smd circle
			(at -0.40005 0 270)
			(size 0 0)
			(layers "B.Cu" "B.Mask" "B.Paste")
			(net "GND")
		)
	)
)
